(kicad_pcb
	(version 20260206)
	(generator "pcbnew")
	(generator_version "10.0")
	(general
		(thickness 1.6)
		(legacy_teardrops no)
	)
	(paper "A4")
	(title_block
		(title "peb — Lightning_PEB_BRD.brd")
		(comment 1 "Lightning (Wiwynn / Facebook NVMe JBOF) / footprints 1652-1658 of 2563")
	)
	(layers
		(0 "F.Cu" signal "TOP")
		(4 "In1.Cu" signal "L2GND")
		(6 "In2.Cu" signal "L3")
		(8 "In3.Cu" signal "L4VCC")
		(10 "In4.Cu" signal "L5VCC")
		(12 "In5.Cu" signal "L6")
		(14 "In6.Cu" signal "L7GND")
		(2 "B.Cu" signal "BOTTOM")
		(9 "F.Adhes" user "F.Adhesive")
		(11 "B.Adhes" user "B.Adhesive")
		(13 "F.Paste" user "Package Geometry/Pastemask Top")
		(15 "B.Paste" user "Package Geometry/Pastemask Bottom")
		(5 "F.SilkS" user "Ref Des/Silkscreen Top")
		(7 "B.SilkS" user "Ref Des/Silkscreen Bottom")
		(1 "F.Mask" user "Board Geometry/Soldermask Top")
		(3 "B.Mask" user "Board Geometry/Soldermask Bottom")
		(17 "Dwgs.User" user "User.Drawings")
		(19 "Cmts.User" user "User.Comments")
		(21 "Eco1.User" user "User.Eco1")
		(23 "Eco2.User" user "User.Eco2")
		(25 "Edge.Cuts" user "Board Geometry/Outline")
		(27 "Margin" user)
		(31 "F.CrtYd" user "Package Geometry/Place Bound Top")
		(29 "B.CrtYd" user "Package Geometry/Place Bound Bottom")
		(35 "F.Fab" user "Ref Des/Assembly Top")
		(33 "B.Fab" user "Ref Des/Assembly Bottom")
	)
	(footprint ""
		(layer "F.Cu")
		(at 134.1882 -41.10101 -90)
		(property "Reference" "R756"
			(at 0 0 270)
			(layer "F.SilkS")
			(hide yes)
			(effects
				(font
					(size 1.27 1.27)
				)
			)
		)
		(property "Value" "0R2J-2-GP"
			(at 0.064008 -3.993896 270)
			(unlocked yes)
			(layer "F.Fab")
			(hide yes)
			(effects
				(font
					(size 1.016 1.016)
					(thickness 0.1524)
				)
			)
		)
		(property "Device Type" "R402H16"
			(at 0.064008 -5.517896 270)
			(unlocked yes)
			(layer "F.Fab")
			(hide yes)
			(effects
				(font
					(size 1.016 1.016)
					(thickness 0.1524)
				)
			)
		)
		(duplicate_pad_numbers_are_jumpers no)
		(fp_line
			(start -0.508 -0.9398)
			(end -0.508 0.9398)
			(stroke
				(width 0.1524)
				(type default)
			)
			(layer "F.SilkS")
		)
		(fp_line
			(start 0.508 -0.9398)
			(end -0.508 -0.9398)
			(stroke
				(width 0.1524)
				(type default)
			)
			(layer "F.SilkS")
		)
		(fp_rect
			(start -0.508 0.9398)
			(end 0.508 -0.9398)
			(stroke
				(width 0)
				(type default)
			)
			(fill no)
			(layer "F.CrtYd")
		)
		(fp_rect
			(start -0.508 0.9398)
			(end 0.508 -0.9398)
			(stroke
				(width 0)
				(type default)
			)
			(fill no)
			(layer "F.Fab")
		)
		(pad "1" smd custom
			(at 0 -0.4445 270)
			(size 0.1397 0.1397)
			(layers "F.Cu" "F.Mask" "F.Paste")
			(net "DUT_TDI")
			(options
				(clearance outline)
				(anchor circle)
			)
			(primitives
				(gr_poly
					(pts
						(arc
							(start -0.1778 -0.2794)
							(mid -0.249642 -0.249642)
							(end -0.2794 -0.1778)
						)
						(arc
							(start -0.2794 0.1778)
							(mid -0.249642 0.249642)
							(end -0.1778 0.2794)
						)
						(arc
							(start 0.1778 0.2794)
							(mid 0.249642 0.249642)
							(end 0.2794 0.1778)
						)
						(arc
							(start 0.2794 -0.1778)
							(mid 0.249642 -0.249642)
							(end 0.1778 -0.2794)
						)
					)
					(width 0)
					(fill yes)
				)
			)
		)
		(pad "2" smd custom
			(at 0 0.4445 270)
			(size 0.1397 0.1397)
			(layers "F.Cu" "F.Mask" "F.Paste")
			(net "EJTAG_TDI")
			(options
				(clearance outline)
				(anchor circle)
			)
			(primitives
				(gr_poly
					(pts
						(arc
							(start -0.1778 -0.2794)
							(mid -0.249642 -0.249642)
							(end -0.2794 -0.1778)
						)
						(arc
							(start -0.2794 0.1778)
							(mid -0.249642 0.249642)
							(end -0.1778 0.2794)
						)
						(arc
							(start 0.1778 0.2794)
							(mid 0.249642 0.249642)
							(end 0.2794 0.1778)
						)
						(arc
							(start 0.2794 -0.1778)
							(mid 0.249642 -0.249642)
							(end 0.1778 -0.2794)
						)
					)
					(width 0)
					(fill yes)
				)
			)
		)
	)
	(footprint ""
		(layer "F.Cu")
		(at 210.884008 -4.064)
		(property "Reference" "R680"
			(at 0 0 0)
			(layer "F.SilkS")
			(hide yes)
			(effects
				(font
					(size 1.27 1.27)
				)
			)
		)
		(property "Value" "100KR2F-L1-GP"
			(at 0.064008 -3.993896 0)
			(unlocked yes)
			(layer "F.Fab")
			(hide yes)
			(effects
				(font
					(size 1.016 1.016)
					(thickness 0.1524)
				)
			)
		)
		(property "Device Type" "R402H16"
			(at 0.064008 -5.517896 0)
			(unlocked yes)
			(layer "F.Fab")
			(hide yes)
			(effects
				(font
					(size 1.016 1.016)
					(thickness 0.1524)
				)
			)
		)
		(duplicate_pad_numbers_are_jumpers no)
		(fp_line
			(start -0.508 -0.9398)
			(end -0.508 0.9398)
			(stroke
				(width 0.1524)
				(type default)
			)
			(layer "F.SilkS")
		)
		(fp_line
			(start 0.508 -0.9398)
			(end -0.508 -0.9398)
			(stroke
				(width 0.1524)
				(type default)
			)
			(layer "F.SilkS")
		)
		(fp_rect
			(start -0.508 0.9398)
			(end 0.508 -0.9398)
			(stroke
				(width 0)
				(type default)
			)
			(fill no)
			(layer "F.CrtYd")
		)
		(fp_rect
			(start -0.508 0.9398)
			(end 0.508 -0.9398)
			(stroke
				(width 0)
				(type default)
			)
			(fill no)
			(layer "F.Fab")
		)
		(pad "1" smd custom
			(at 0 -0.4445)
			(size 0.1397 0.1397)
			(layers "F.Cu" "F.Mask" "F.Paste")
			(net "HOST6_RST_N")
			(options
				(clearance outline)
				(anchor circle)
			)
			(primitives
				(gr_poly
					(pts
						(arc
							(start -0.1778 -0.2794)
							(mid -0.249642 -0.249642)
							(end -0.2794 -0.1778)
						)
						(arc
							(start -0.2794 0.1778)
							(mid -0.249642 0.249642)
							(end -0.1778 0.2794)
						)
						(arc
							(start 0.1778 0.2794)
							(mid 0.249642 0.249642)
							(end 0.2794 0.1778)
						)
						(arc
							(start 0.2794 -0.1778)
							(mid 0.249642 -0.249642)
							(end 0.1778 -0.2794)
						)
					)
					(width 0)
					(fill yes)
				)
			)
		)
		(pad "2" smd custom
			(at 0 0.4445)
			(size 0.1397 0.1397)
			(layers "F.Cu" "F.Mask" "F.Paste")
			(net "GND")
			(options
				(clearance outline)
				(anchor circle)
			)
			(primitives
				(gr_poly
					(pts
						(arc
							(start -0.1778 -0.2794)
							(mid -0.249642 -0.249642)
							(end -0.2794 -0.1778)
						)
						(arc
							(start -0.2794 0.1778)
							(mid -0.249642 0.249642)
							(end -0.1778 0.2794)
						)
						(arc
							(start 0.1778 0.2794)
							(mid 0.249642 0.249642)
							(end 0.2794 0.1778)
						)
						(arc
							(start 0.2794 -0.1778)
							(mid 0.249642 -0.249642)
							(end 0.1778 -0.2794)
						)
					)
					(width 0)
					(fill yes)
				)
			)
		)
	)
	(footprint ""
		(layer "F.Cu")
		(at 124.069348 -48.453294 -90)
		(property "Reference" "JP4"
			(at 0 0 270)
			(layer "F.SilkS")
			(hide yes)
			(effects
				(font
					(size 1.27 1.27)
				)
			)
		)
		(property "Value" "PIN-CON3-S-GP"
			(at -5.588 -5.3086 270)
			(unlocked yes)
			(layer "F.Fab")
			(hide yes)
			(effects
				(font
					(size 1.016 1.016)
					(thickness 0.1524)
				)
			)
		)
		(property "Device Type" "21S-91-03GB01"
			(at -5.588 -6.8326 270)
			(unlocked yes)
			(layer "F.Fab")
			(hide yes)
			(effects
				(font
					(size 1.016 1.016)
					(thickness 0.1524)
				)
			)
		)
		(duplicate_pad_numbers_are_jumpers no)
		(fp_line
			(start -3.8862 1.4986)
			(end 3.8862 1.4986)
			(stroke
				(width 0.1524)
				(type default)
			)
			(layer "F.SilkS")
		)
		(fp_line
			(start 3.8862 1.4986)
			(end 3.8862 -1.4986)
			(stroke
				(width 0.1524)
				(type default)
			)
			(layer "F.SilkS")
		)
		(fp_line
			(start -4.0132 -0.3556)
			(end -4.0132 -1.6256)
			(stroke
				(width 0.4064)
				(type default)
			)
			(layer "F.SilkS")
		)
		(fp_line
			(start -3.8862 -1.4986)
			(end -3.8862 1.4986)
			(stroke
				(width 0.1524)
				(type default)
			)
			(layer "F.SilkS")
		)
		(fp_line
			(start 3.8862 -1.4986)
			(end -3.8862 -1.4986)
			(stroke
				(width 0.1524)
				(type default)
			)
			(layer "F.SilkS")
		)
		(fp_line
			(start -4.0132 -1.6256)
			(end -2.7432 -1.6256)
			(stroke
				(width 0.4064)
				(type default)
			)
			(layer "F.SilkS")
		)
		(fp_circle
			(center -2.54 0)
			(end -2.54 -1.0668)
			(stroke
				(width 0.3048)
				(type default)
			)
			(fill no)
			(layer "F.SilkS")
		)
		(fp_circle
			(center 0 0)
			(end 0 -1.0668)
			(stroke
				(width 0.3048)
				(type default)
			)
			(fill no)
			(layer "F.SilkS")
		)
		(fp_circle
			(center 2.54 0)
			(end 2.54 -1.0668)
			(stroke
				(width 0.3048)
				(type default)
			)
			(fill no)
			(layer "F.SilkS")
		)
		(fp_rect
			(start -3.6322 1.2446)
			(end 3.6322 -1.2446)
			(stroke
				(width 0)
				(type default)
			)
			(fill no)
			(layer "F.CrtYd")
		)
		(fp_poly
			(pts
				(xy 4.1402 -1.2446) (xy -3.6322 -1.2446) (xy -3.6322 1.2446) (xy 3.6322 1.2446) (xy 3.6322 -1.2319)
				(xy 4.1402 -1.2319) (xy 4.1402 1.7526) (xy -4.1402 1.7526) (xy -4.1402 -1.7526) (xy 4.1402 -1.7526)
			)
			(stroke
				(width 0)
				(type default)
			)
			(fill no)
			(layer "F.CrtYd")
		)
		(fp_rect
			(start -4.1402 1.7526)
			(end 4.1402 -1.7526)
			(stroke
				(width 0)
				(type default)
			)
			(fill no)
			(layer "F.Fab")
		)
		(pad "1" thru_hole circle
			(at -2.54 0 270)
			(size 1.4224 1.4224)
			(drill 1.016)
			(layers "*.Cu" "*.Mask")
			(remove_unused_layers no)
			(net "BMC_ADD1_PWR")
			(clearance 0.1524)
			(thermal_gap 0.1524)
		)
		(pad "2" thru_hole circle
			(at 0 0 270)
			(size 1.4224 1.4224)
			(drill 1.016)
			(layers "*.Cu" "*.Mask")
			(remove_unused_layers no)
			(net "BMC_ADD1")
			(clearance 0.1524)
			(thermal_gap 0.1524)
		)
		(pad "3" thru_hole circle
			(at 2.54 0 270)
			(size 1.4224 1.4224)
			(drill 1.016)
			(layers "*.Cu" "*.Mask")
			(remove_unused_layers no)
			(net "BMC_ADD1_GND")
			(clearance 0.1524)
			(thermal_gap 0.1524)
		)
	)
	(footprint ""
		(layer "F.Cu")
		(at 23.517352 -102.20071)
		(property "Reference" "U204"
			(at 0 0 0)
			(layer "F.SilkS")
			(hide yes)
			(effects
				(font
					(size 1.27 1.27)
				)
			)
		)
		(property "Value" "LMV331IDCKRG4-GP"
			(at -2.3368 -8.6868 0)
			(unlocked yes)
			(layer "F.Fab")
			(hide yes)
			(effects
				(font
					(size 1.016 1.016)
					(thickness 0.1524)
				)
			)
		)
		(property "Device Type" "SC70-5H44"
			(at -2.3114 -10.414 0)
			(unlocked yes)
			(layer "F.Fab")
			(hide yes)
			(effects
				(font
					(size 1.016 1.016)
					(thickness 0.1524)
				)
			)
		)
		(duplicate_pad_numbers_are_jumpers no)
		(fp_line
			(start -1.27 -1.7018)
			(end 1.27 -1.7018)
			(stroke
				(width 0.1524)
				(type default)
			)
			(layer "F.SilkS")
		)
		(fp_line
			(start -1.27 1.7018)
			(end -1.27 -1.7018)
			(stroke
				(width 0.1524)
				(type default)
			)
			(layer "F.SilkS")
		)
		(fp_line
			(start 0.6604 -1.8034)
			(end 1.3843 -1.8034)
			(stroke
				(width 0.3302)
				(type default)
			)
			(layer "F.SilkS")
		)
		(fp_line
			(start 1.27 -1.7018)
			(end 1.27 1.7018)
			(stroke
				(width 0.1524)
				(type default)
			)
			(layer "F.SilkS")
		)
		(fp_line
			(start 1.27 1.7018)
			(end -1.27 1.7018)
			(stroke
				(width 0.1524)
				(type default)
			)
			(layer "F.SilkS")
		)
		(fp_line
			(start 1.3843 -1.8034)
			(end 1.3843 -1.1176)
			(stroke
				(width 0.3302)
				(type default)
			)
			(layer "F.SilkS")
		)
		(fp_rect
			(start -1.524 1.9558)
			(end 1.524 -1.9558)
			(stroke
				(width 0)
				(type default)
			)
			(fill no)
			(layer "F.CrtYd")
		)
		(fp_poly
			(pts
				(xy -1.524 -1.9558) (xy 1.524 -1.9558) (xy 1.524 1.9558) (xy -1.524 1.9558)
			)
			(stroke
				(width 0)
				(type default)
			)
			(fill no)
			(layer "F.Fab")
		)
		(pad "1" smd rect
			(at 0.65024 -0.8255)
			(size 0.4064 1.2192)
			(layers "F.Cu" "F.Mask" "F.Paste")
			(net "FM_TPM_PRES_RST_N")
		)
		(pad "2" smd rect
			(at 0 -0.8255)
			(size 0.4064 1.2192)
			(layers "F.Cu" "F.Mask" "F.Paste")
			(net "GND")
		)
		(pad "3" smd rect
			(at -0.65024 -0.8255)
			(size 0.4064 1.2192)
			(layers "F.Cu" "F.Mask" "F.Paste")
			(net "VREF_2V2")
		)
		(pad "4" smd rect
			(at -0.65024 0.8255)
			(size 0.4064 1.2192)
			(layers "F.Cu" "F.Mask" "F.Paste")
			(net "FM_TPM_PRES_N")
		)
		(pad "5" smd rect
			(at 0.65024 0.8255)
			(size 0.4064 1.2192)
			(layers "F.Cu" "F.Mask" "F.Paste")
			(net "P5V_STBY")
		)
	)
	(footprint ""
		(layer "F.Cu")
		(at 53.721 -139.827 90)
		(property "Reference" "R150"
			(at 0 0 90)
			(layer "F.SilkS")
			(hide yes)
			(effects
				(font
					(size 1.27 1.27)
				)
			)
		)
		(property "Value" "4K7R2F-GP"
			(at 0.064008 -3.993896 90)
			(unlocked yes)
			(layer "F.Fab")
			(hide yes)
			(effects
				(font
					(size 1.016 1.016)
					(thickness 0.1524)
				)
			)
		)
		(property "Device Type" "R402H16"
			(at 0.064008 -5.517896 90)
			(unlocked yes)
			(layer "F.Fab")
			(hide yes)
			(effects
				(font
					(size 1.016 1.016)
					(thickness 0.1524)
				)
			)
		)
		(duplicate_pad_numbers_are_jumpers no)
		(fp_line
			(start 0.508 -0.9398)
			(end -0.508 -0.9398)
			(stroke
				(width 0.1524)
				(type default)
			)
			(layer "F.SilkS")
		)
		(fp_line
			(start -0.508 -0.9398)
			(end -0.508 0.9398)
			(stroke
				(width 0.1524)
				(type default)
			)
			(layer "F.SilkS")
		)
		(fp_rect
			(start -0.508 0.9398)
			(end 0.508 -0.9398)
			(stroke
				(width 0)
				(type default)
			)
			(fill no)
			(layer "F.CrtYd")
		)
		(fp_rect
			(start -0.508 0.9398)
			(end 0.508 -0.9398)
			(stroke
				(width 0)
				(type default)
			)
			(fill no)
			(layer "F.Fab")
		)
		(pad "1" smd custom
			(at 0 -0.4445 90)
			(size 0.1397 0.1397)
			(layers "F.Cu" "F.Mask" "F.Paste")
			(net "CBL_PRSNT_N_7")
			(options
				(clearance outline)
				(anchor circle)
			)
			(primitives
				(gr_poly
					(pts
						(arc
							(start -0.1778 -0.2794)
							(mid -0.249642 -0.249642)
							(end -0.2794 -0.1778)
						)
						(arc
							(start -0.2794 0.1778)
							(mid -0.249642 0.249642)
							(end -0.1778 0.2794)
						)
						(arc
							(start 0.1778 0.2794)
							(mid 0.249642 0.249642)
							(end 0.2794 0.1778)
						)
						(arc
							(start 0.2794 -0.1778)
							(mid 0.249642 -0.249642)
							(end 0.1778 -0.2794)
						)
					)
					(width 0)
					(fill yes)
				)
			)
		)
		(pad "2" smd custom
			(at 0 0.4445 90)
			(size 0.1397 0.1397)
			(layers "F.Cu" "F.Mask" "F.Paste")
			(net "P3V3_STBY")
			(options
				(clearance outline)
				(anchor circle)
			)
			(primitives
				(gr_poly
					(pts
						(arc
							(start -0.1778 -0.2794)
							(mid -0.249642 -0.249642)
							(end -0.2794 -0.1778)
						)
						(arc
							(start -0.2794 0.1778)
							(mid -0.249642 0.249642)
							(end -0.1778 0.2794)
						)
						(arc
							(start 0.1778 0.2794)
							(mid 0.249642 0.249642)
							(end 0.2794 0.1778)
						)
						(arc
							(start 0.2794 -0.1778)
							(mid 0.249642 -0.249642)
							(end 0.1778 -0.2794)
						)
					)
					(width 0)
					(fill yes)
				)
			)
		)
	)
	(footprint ""
		(layer "B.Cu")
		(at 227.6856 -35.0012 -90)
		(property "Reference" "C567"
			(at 0 0 90)
			(layer "B.SilkS")
			(hide yes)
			(effects
				(font
					(size 1.27 1.27)
				)
				(justify mirror)
			)
		)
		(property "Value" "SCD1U16V1KX-1-GP"
			(at 2.8321 -1.7399 270)
			(unlocked yes)
			(layer "B.Fab")
			(hide yes)
			(effects
				(font
					(size 1.016 1.016)
					(thickness 0.1524)
				)
				(justify mirror)
			)
		)
		(property "Device Type" "C0201H13"
			(at 2.8321 -3.2639 270)
			(unlocked yes)
			(layer "B.Fab")
			(hide yes)
			(effects
				(font
					(size 1.016 1.016)
					(thickness 0.1524)
				)
				(justify mirror)
			)
		)
		(duplicate_pad_numbers_are_jumpers no)
		(fp_rect
			(start 0.2794 0.6477)
			(end -0.2794 -0.6477)
			(stroke
				(width 0)
				(type default)
			)
			(fill no)
			(layer "B.CrtYd")
		)
		(fp_rect
			(start 0.2794 0.6477)
			(end -0.2794 -0.6477)
			(stroke
				(width 0)
				(type default)
			)
			(fill no)
			(layer "B.Fab")
		)
		(pad "1" smd custom
			(at 0 -0.2794 90)
			(size 0.0762 0.0762)
			(layers "B.Cu" "B.Mask" "B.Paste")
			(net "DUT_AVD_PCIE")
			(options
				(clearance outline)
				(anchor circle)
			)
			(primitives
				(gr_poly
					(pts
						(arc
							(start 0.1524 0.127)
							(mid 0.137521 0.162921)
							(end 0.1016 0.1778)
						)
						(arc
							(start -0.1016 0.1778)
							(mid -0.137521 0.162921)
							(end -0.1524 0.127)
						)
						(arc
							(start -0.1524 -0.127)
							(mid -0.137521 -0.162921)
							(end -0.1016 -0.1778)
						)
						(arc
							(start 0.1016 -0.1778)
							(mid 0.137521 -0.162921)
							(end 0.1524 -0.127)
						)
					)
					(width 0)
					(fill yes)
				)
			)
		)
		(pad "2" smd custom
			(at 0 0.2794 90)
			(size 0.0762 0.0762)
			(layers "B.Cu" "B.Mask" "B.Paste")
			(net "GND")
			(options
				(clearance outline)
				(anchor circle)
			)
			(primitives
				(gr_poly
					(pts
						(arc
							(start 0.1524 0.127)
							(mid 0.137521 0.162921)
							(end 0.1016 0.1778)
						)
						(arc
							(start -0.1016 0.1778)
							(mid -0.137521 0.162921)
							(end -0.1524 0.127)
						)
						(arc
							(start -0.1524 -0.127)
							(mid -0.137521 -0.162921)
							(end -0.1016 -0.1778)
						)
						(arc
							(start 0.1016 -0.1778)
							(mid 0.137521 -0.162921)
							(end 0.1524 -0.127)
						)
					)
					(width 0)
					(fill yes)
				)
			)
		)
	)
	(footprint ""
		(layer "B.Cu")
		(at 135.808212 -205.849474)
		(property "Reference" "R3220"
			(at 0 0 0)
			(layer "B.SilkS")
			(hide yes)
			(effects
				(font
					(size 1.27 1.27)
				)
				(justify mirror)
			)
		)
		(property "Value" "0R2J-2-GP"
			(at -0.064008 -3.993896 0)
			(unlocked yes)
			(layer "B.Fab")
			(hide yes)
			(effects
				(font
					(size 1.016 1.016)
					(thickness 0.1524)
				)
				(justify mirror)
			)
		)
		(property "Device Type" "R402H16"
			(at -0.064008 -5.517896 0)
			(unlocked yes)
			(layer "B.Fab")
			(hide yes)
			(effects
				(font
					(size 1.016 1.016)
					(thickness 0.1524)
				)
				(justify mirror)
			)
		)
		(duplicate_pad_numbers_are_jumpers no)
		(fp_line
			(start -0.508 -0.9398)
			(end 0.508 -0.9398)
			(stroke
				(width 0.1524)
				(type default)
			)
			(layer "B.SilkS")
		)
		(fp_line
			(start 0.508 -0.9398)
			(end 0.508 0.9398)
			(stroke
				(width 0.1524)
				(type default)
			)
			(layer "B.SilkS")
		)
		(fp_rect
			(start 0.508 0.9398)
			(end -0.508 -0.9398)
			(stroke
				(width 0)
				(type default)
			)
			(fill no)
			(layer "B.CrtYd")
		)
		(fp_rect
			(start 0.508 0.9398)
			(end -0.508 -0.9398)
			(stroke
				(width 0)
				(type default)
			)
			(fill no)
			(layer "B.Fab")
		)
		(pad "1" smd custom
			(at 0 -0.4445 180)
			(size 0.1397 0.1397)
			(layers "B.Cu" "B.Mask" "B.Paste")
			(net "BMC_SSD_RST#6")
			(options
				(clearance outline)
				(anchor circle)
			)
			(primitives
				(gr_poly
					(pts
						(arc
							(start -0.1778 0.2794)
							(mid -0.249642 0.249642)
							(end -0.2794 0.1778)
						)
						(arc
							(start -0.2794 -0.1778)
							(mid -0.249642 -0.249642)
							(end -0.1778 -0.2794)
						)
						(arc
							(start 0.1778 -0.2794)
							(mid 0.249642 -0.249642)
							(end 0.2794 -0.1778)
						)
						(arc
							(start 0.2794 0.1778)
							(mid 0.249642 0.249642)
							(end 0.1778 0.2794)
						)
					)
					(width 0)
					(fill yes)
				)
			)
		)
		(pad "2" smd custom
			(at 0 0.4445 180)
			(size 0.1397 0.1397)
			(layers "B.Cu" "B.Mask" "B.Paste")
			(net "BMC_SSD_RST#0_A6")
			(options
				(clearance outline)
				(anchor circle)
			)
			(primitives
				(gr_poly
					(pts
						(arc
							(start -0.1778 0.2794)
							(mid -0.249642 0.249642)
							(end -0.2794 0.1778)
						)
						(arc
							(start -0.2794 -0.1778)
							(mid -0.249642 -0.249642)
							(end -0.1778 -0.2794)
						)
						(arc
							(start 0.1778 -0.2794)
							(mid 0.249642 -0.249642)
							(end 0.2794 -0.1778)
						)
						(arc
							(start 0.2794 0.1778)
							(mid 0.249642 0.249642)
							(end 0.1778 0.2794)
						)
					)
					(width 0)
					(fill yes)
				)
			)
		)
	)
)
